# S9S_MB_2U (Grand Teton) — schematic netlist excerpt (pin names and nets, part order shuffled) for the footprints in the layout excerpt that follows; sources: Cadence DE-HDL packaged netlist, KiCad conversion of 03242023_DA0F0TMBIJ0_F0T_Motherboard_J_brd_V01_OCP.brd

R4801  Q_RES  4.7K 5% CHIP  pkg 0402LF  page 144 : A = P3V3_AUX ; B = PRSNT_CABLE_GPU_A3_ISO_N

U332  74LVC2G07DW7  74LVC2G07DW-7 EMPTY  pkg SOT363_0-65_2X1-25XC  page 224
  \1a\  = FM_AC_PWR_BTN_PLD_N
  GND  = GND
  \2a\  = GND
  \2y\  = NC_UXX_2Y
  VCC  = P3V3_AUX
  \1y\  = FM_AC_PWR_BTN_PLD_ISO_R_N

(kicad_pcb
	(version 20260206)
	(generator "pcbnew")
	(generator_version "10.0")
	(general
		(thickness 1.6)
		(legacy_teardrops no)
	)
	(paper "A4")
	(title_block
		(title "03242023_DA0F0TMBIJ0_F0T_Motherboard_J_brd_V01_OCP.brd")
		(comment 1 "Grand Teton / footprints 1600-1601 of 6105")
	)
	(layers
		(0 "F.Cu" signal "TOP")
		(4 "In1.Cu" signal "GND")
		(6 "In2.Cu" signal "IN1")
		(8 "In3.Cu" signal "GND1")
		(10 "In4.Cu" signal "IN2")
		(12 "In5.Cu" signal "GND2")
		(14 "In6.Cu" signal "IN3")
		(16 "In7.Cu" signal "GND3")
		(18 "In8.Cu" signal "VCC")
		(20 "In9.Cu" signal "VCC1")
		(22 "In10.Cu" signal "GND4")
		(24 "In11.Cu" signal "IN4")
		(26 "In12.Cu" signal "GND5")
		(28 "In13.Cu" signal "IN5")
		(30 "In14.Cu" signal "GND6")
		(32 "In15.Cu" signal "IN6")
		(34 "In16.Cu" signal "GND7")
		(2 "B.Cu" signal "BOTTOM")
		(9 "F.Adhes" user "F.Adhesive")
		(11 "B.Adhes" user "B.Adhesive")
		(13 "F.Paste" user "Package Geometry/Pastemask Top")
		(15 "B.Paste" user "Package Geometry/Pastemask Bottom")
		(5 "F.SilkS" user "Ref Des/Silkscreen Top")
		(7 "B.SilkS" user "Ref Des/Silkscreen Bottom")
		(1 "F.Mask" user "Board Geometry/Soldermask Top")
		(3 "B.Mask" user "Board Geometry/Soldermask Bottom")
		(17 "Dwgs.User" user "User.Drawings")
		(19 "Cmts.User" user "User.Comments")
		(21 "Eco1.User" user "User.Eco1")
		(23 "Eco2.User" user "User.Eco2")
		(25 "Edge.Cuts" user "Board Geometry/Outline")
		(27 "Margin" user)
		(31 "F.CrtYd" user "Package Geometry/Place Bound Top")
		(29 "B.CrtYd" user "Package Geometry/Place Bound Bottom")
		(35 "F.Fab" user "Ref Des/Assembly Top")
		(33 "B.Fab" user "Ref Des/Assembly Bottom")
	)
	(footprint ""
		(layer "F.Cu")
		(at 212.299296 -120.457214 180)
		(property "Reference" "U332"
			(at 1.352296 -1.992884 0)
			(unlocked yes)
			(layer "F.SilkS")
			(effects
				(font
					(size 0.7874 0.5842)
					(thickness 0.1524)
				)
				(justify left)
			)
		)
		(property "Value" ""
			(at 0 0 180)
			(layer "F.Fab")
			(effects
				(font
					(size 1.27 1.27)
				)
			)
		)
		(duplicate_pad_numbers_are_jumpers no)
		(fp_line
			(start 1.38176 1.100074)
			(end 1.38176 -1.100074)
			(stroke
				(width 0.1524)
				(type default)
			)
			(layer "F.SilkS")
		)
		(fp_line
			(start 1.38176 -1.100074)
			(end 0.592074 -1.100074)
			(stroke
				(width 0.1524)
				(type default)
			)
			(layer "F.SilkS")
		)
		(fp_line
			(start 0.592074 -1.100074)
			(end 0 -0.508)
			(stroke
				(width 0.1524)
				(type default)
			)
			(layer "F.SilkS")
		)
		(fp_line
			(start 0 -0.508)
			(end -0.592074 -1.100074)
			(stroke
				(width 0.1524)
				(type default)
			)
			(layer "F.SilkS")
		)
		(fp_line
			(start -0.592074 -1.100074)
			(end -1.38176 -1.100074)
			(stroke
				(width 0.1524)
				(type default)
			)
			(layer "F.SilkS")
		)
		(fp_line
			(start -1.38176 1.100074)
			(end 1.38176 1.100074)
			(stroke
				(width 0.1524)
				(type default)
			)
			(layer "F.SilkS")
		)
		(fp_line
			(start -1.38176 -1.100074)
			(end -1.38176 1.100074)
			(stroke
				(width 0.1524)
				(type default)
			)
			(layer "F.SilkS")
		)
		(fp_poly
			(pts
				(xy -1.9431 -0.870204) (xy -1.50241 -0.649986) (xy -1.9431 -0.429768)
			)
			(stroke
				(width 0)
				(type default)
			)
			(fill yes)
			(layer "F.SilkS")
		)
		(fp_line
			(start 0.674878 1.100074)
			(end 0.674878 -1.100074)
			(stroke
				(width 0.1)
				(type default)
			)
			(layer "F.Fab")
		)
		(fp_line
			(start 0.674878 -1.100074)
			(end -0.674878 -1.100074)
			(stroke
				(width 0.1)
				(type default)
			)
			(layer "F.Fab")
		)
		(fp_line
			(start -0.674878 1.100074)
			(end 0.674878 1.100074)
			(stroke
				(width 0.1)
				(type default)
			)
			(layer "F.Fab")
		)
		(fp_line
			(start -0.674878 -1.100074)
			(end -0.674878 1.100074)
			(stroke
				(width 0.1)
				(type default)
			)
			(layer "F.Fab")
		)
		(fp_poly
			(pts
				(xy -1.9431 -0.870204) (xy -1.50241 -0.649986) (xy -1.9431 -0.429768)
			)
			(stroke
				(width 0)
				(type default)
			)
			(fill yes)
			(layer "F.Fab")
		)
		(pad "1" smd rect
			(at -0.94996 -0.649986 90)
			(size 0.4318 0.6096)
			(layers "F.Cu" "F.Mask" "F.Paste")
			(net "FM_AC_PWR_BTN_PLD_N")
		)
		(pad "2" smd rect
			(at -0.94996 0 90)
			(size 0.4318 0.6096)
			(layers "F.Cu" "F.Mask" "F.Paste")
			(net "GND")
		)
		(pad "3" smd rect
			(at -0.94996 0.649986 90)
			(size 0.4318 0.6096)
			(layers "F.Cu" "F.Mask" "F.Paste")
			(net "GND")
		)
		(pad "4" smd rect
			(at 0.94996 0.649986 90)
			(size 0.4318 0.6096)
			(layers "F.Cu" "F.Mask" "F.Paste")
			(net "NC_UXX_2Y")
		)
		(pad "5" smd rect
			(at 0.94996 0 90)
			(size 0.4318 0.6096)
			(layers "F.Cu" "F.Mask" "F.Paste")
			(net "P3V3_AUX")
		)
		(pad "6" smd rect
			(at 0.94996 -0.649986 90)
			(size 0.4318 0.6096)
			(layers "F.Cu" "F.Mask" "F.Paste")
			(net "FM_AC_PWR_BTN_PLD_ISO_R_N")
		)
	)
	(footprint ""
		(layer "F.Cu")
		(at 365.2012 -413.6898 180)
		(property "Reference" "R4801"
			(at 0 0 180)
			(layer "F.SilkS")
			(hide yes)
			(effects
				(font
					(size 1.27 1.27)
				)
			)
		)
		(property "Value" ""
			(at 0 0 180)
			(layer "F.Fab")
			(effects
				(font
					(size 1.27 1.27)
				)
			)
		)
		(duplicate_pad_numbers_are_jumpers no)
		(fp_line
			(start 0.7874 0.4064)
			(end -0.7874 0.4064)
			(stroke
				(width 0.1524)
				(type default)
			)
			(layer "F.SilkS")
		)
		(fp_line
			(start 0.7874 -0.4064)
			(end 0.7874 0.4064)
			(stroke
				(width 0.1524)
				(type default)
			)
			(layer "F.SilkS")
		)
		(fp_line
			(start -0.7874 0.4064)
			(end -0.7874 -0.4064)
			(stroke
				(width 0.1524)
				(type default)
			)
			(layer "F.SilkS")
		)
		(fp_line
			(start -0.7874 -0.4064)
			(end 0.7874 -0.4064)
			(stroke
				(width 0.1524)
				(type default)
			)
			(layer "F.SilkS")
		)
		(fp_line
			(start 0.67945 0.3048)
			(end 0.120396 0.3048)
			(stroke
				(width 0.1)
				(type default)
			)
			(layer "F.Fab")
		)
		(fp_line
			(start 0.67945 -0.3048)
			(end 0.67945 0.3048)
			(stroke
				(width 0.1)
				(type default)
			)
			(layer "F.Fab")
		)
		(fp_line
			(start 0.12065 -0.2794)
			(end 0.12065 -0.3048)
			(stroke
				(width 0.1)
				(type default)
			)
			(layer "F.Fab")
		)
		(fp_line
			(start 0.12065 -0.3048)
			(end 0.67945 -0.3048)
			(stroke
				(width 0.1)
				(type default)
			)
			(layer "F.Fab")
		)
		(fp_line
			(start 0.120396 0.3048)
			(end 0.120396 0.2794)
			(stroke
				(width 0.1)
				(type default)
			)
			(layer "F.Fab")
		)
		(fp_line
			(start 0.120396 0.2794)
			(end -0.12065 0.2794)
			(stroke
				(width 0.1)
				(type default)
			)
			(layer "F.Fab")
		)
		(fp_line
			(start -0.12065 0.3048)
			(end -0.67945 0.3048)
			(stroke
				(width 0.1)
				(type default)
			)
			(layer "F.Fab")
		)
		(fp_line
			(start -0.12065 0.2794)
			(end -0.12065 0.3048)
			(stroke
				(width 0.1)
				(type default)
			)
			(layer "F.Fab")
		)
		(fp_line
			(start -0.12065 -0.2794)
			(end 0.12065 -0.2794)
			(stroke
				(width 0.1)
				(type default)
			)
			(layer "F.Fab")
		)
		(fp_line
			(start -0.12065 -0.305054)
			(end -0.12065 -0.2794)
			(stroke
				(width 0.1)
				(type default)
			)
			(layer "F.Fab")
		)
		(fp_line
			(start -0.67945 0.3048)
			(end -0.67945 -0.305054)
			(stroke
				(width 0.1)
				(type default)
			)
			(layer "F.Fab")
		)
		(fp_line
			(start -0.67945 -0.305054)
			(end -0.12065 -0.305054)
			(stroke
				(width 0.1)
				(type default)
			)
			(layer "F.Fab")
		)
		(pad "1" smd circle
			(at -0.40005 0 180)
			(size 0 0)
			(layers "F.Cu" "F.Mask" "F.Paste")
			(net "P3V3_AUX")
		)
		(pad "2" smd circle
			(at 0.40005 0 180)
			(size 0 0)
			(layers "F.Cu" "F.Mask" "F.Paste")
			(net "PRSNT_CABLE_GPU_A3_ISO_N")
		)
	)
)
